(kicad_pcb
	(version 20240108)
	(generator "pcbnew")
	(generator_version "8.0")
	(general
		(thickness 1.62)
		(legacy_teardrops no)
	)
	(paper "A4")
	(title_block
		(title "Jetson Orin Baseboard")
		(date "2025-03-12")
		(rev "1.3.4")
		(company "Antmicro Ltd")
		(comment 1 "www.antmicro.com")
		(comment 9 "footprints 113-115 of 677")
	)
	(layers
		(0 "F.Cu" signal)
		(1 "In1.Cu" signal)
		(2 "In2.Cu" signal)
		(3 "In3.Cu" signal)
		(4 "In4.Cu" jumper)
		(5 "In5.Cu" signal)
		(6 "In6.Cu" signal)
		(31 "B.Cu" signal)
		(32 "B.Adhes" user "B.Adhesive")
		(33 "F.Adhes" user "F.Adhesive")
		(34 "B.Paste" user)
		(35 "F.Paste" user)
		(36 "B.SilkS" user "B.Silkscreen")
		(37 "F.SilkS" user "F.Silkscreen")
		(38 "B.Mask" user)
		(39 "F.Mask" user)
		(40 "Dwgs.User" user "User.Drawings")
		(41 "Cmts.User" user "User.Comments")
		(42 "Eco1.User" user "User.Eco1")
		(43 "Eco2.User" user "User.Eco2")
		(44 "Edge.Cuts" user)
		(45 "Margin" user)
		(46 "B.CrtYd" user "B.Courtyard")
		(47 "F.CrtYd" user "F.Courtyard")
		(48 "B.Fab" user)
		(49 "F.Fab" user)
	)
	(footprint "antmicro-footprints:R_Array_4x0402"
		(layer "F.Cu")
		(at 139.25 105.6 90)
		(property "Reference" "R63"
			(at -1.05 -0.95 90)
			(layer "F.SilkS")
			(effects
				(font
					(size 0.7 0.7)
					(thickness 0.15)
				)
				(justify left bottom)
			)
		)
		(property "Value" "R_4x330R_0402_array"
			(at -1.5 2 90)
			(layer "F.Fab")
			(effects
				(font
					(size 0.7 0.7)
					(thickness 0.15)
				)
				(justify left bottom)
			)
		)
		(property "Footprint" "antmicro-footprints:R_Array_4x0402"
			(at 0 0 90)
			(layer "F.Fab")
			(hide yes)
			(effects
				(font
					(size 1.27 1.27)
					(thickness 0.15)
				)
			)
		)
		(property "Datasheet" "http://industrial.panasonic.com/cdbs/www-data/pdf/AOC0000/AOC0000C14.pdf"
			(at 0 0 90)
			(layer "F.Fab")
			(hide yes)
			(effects
				(font
					(size 1.27 1.27)
					(thickness 0.15)
				)
			)
		)
		(property "Author" "Antmicro"
			(at 244.85 -33.65 0)
			(layer "F.Fab")
			(hide yes)
			(effects
				(font
					(size 1 1)
					(thickness 0.15)
				)
			)
		)
		(property "License" "Apache-2.0"
			(at 244.85 -33.65 0)
			(layer "F.Fab")
			(hide yes)
			(effects
				(font
					(size 1 1)
					(thickness 0.15)
				)
			)
		)
		(property "MPN" "EXB-28V331JX"
			(at 244.85 -33.65 0)
			(layer "F.Fab")
			(hide yes)
			(effects
				(font
					(size 1 1)
					(thickness 0.15)
				)
			)
		)
		(property "Manufacturer" "Panasonic"
			(at 244.85 -33.65 0)
			(layer "F.Fab")
			(hide yes)
			(effects
				(font
					(size 1 1)
					(thickness 0.15)
				)
			)
		)
		(property "Val" "R_4x330R_0402"
			(at 244.85 -33.65 0)
			(layer "F.Fab")
			(hide yes)
			(effects
				(font
					(size 1 1)
					(thickness 0.15)
				)
			)
		)
		(sheetname "Peripherals")
		(sheetfile "peripherals.kicad_sch")
		(attr smd)
		(fp_line
			(start -1.17 -0.5)
			(end -1.17 0.498)
			(stroke
				(width 0.15)
				(type solid)
			)
			(layer "F.SilkS")
		)
		(fp_line
			(start 1.167 0.498)
			(end 1.167 -0.5)
			(stroke
				(width 0.15)
				(type solid)
			)
			(layer "F.SilkS")
		)
		(fp_rect
			(start -1.2 -0.9)
			(end 1.2 0.9)
			(stroke
				(width 0.05)
				(type solid)
			)
			(fill none)
			(layer "F.CrtYd")
		)
		(fp_line
			(start 0.998 -0.5)
			(end 0.998 0.498)
			(stroke
				(width 0.15)
				(type solid)
			)
			(layer "F.Fab")
		)
		(fp_line
			(start -1 -0.5)
			(end 0.998 -0.5)
			(stroke
				(width 0.15)
				(type solid)
			)
			(layer "F.Fab")
		)
		(fp_line
			(start 0.998 0.498)
			(end -1 0.498)
			(stroke
				(width 0.15)
				(type solid)
			)
			(layer "F.Fab")
		)
		(fp_line
			(start -1 0.498)
			(end -1 -0.5)
			(stroke
				(width 0.15)
				(type solid)
			)
			(layer "F.Fab")
		)
		(fp_text user "Author: Antmicro"
			(at -1.5 4.5 90)
			(layer "F.Fab")
			(hide yes)
			(effects
				(font
					(size 0.7 0.7)
					(thickness 0.15)
				)
				(justify left bottom)
			)
		)
		(fp_text user "License: Apache-2.0"
			(at -1.5 5.75 90)
			(layer "F.Fab")
			(hide yes)
			(effects
				(font
					(size 0.7 0.7)
					(thickness 0.15)
				)
				(justify left bottom)
			)
		)
		(fp_text user "${REFERENCE}"
			(at -1.5 3.25 90)
			(layer "F.Fab")
			(hide yes)
			(effects
				(font
					(size 0.7 0.7)
					(thickness 0.15)
				)
				(justify left bottom)
			)
		)
		(pad "1" smd roundrect
			(at -0.802 0.45 90)
			(size 0.4 0.5)
			(layers "F.Cu" "F.Paste" "F.Mask")
			(roundrect_rratio 0.25)
			(net 607 "/Peripherals/~{SPI0_CS1_CONN}")
			(pinfunction "R1.1")
			(pintype "passive")
		)
		(pad "2" smd roundrect
			(at -0.272 0.45 90)
			(size 0.4 0.5)
			(layers "F.Cu" "F.Paste" "F.Mask")
			(roundrect_rratio 0.25)
			(net 595 "/Peripherals/~{SPI0_CS0_CONN}")
			(pinfunction "R2.1")
			(pintype "passive")
		)
		(pad "3" smd roundrect
			(at 0.27 0.45 90)
			(size 0.4 0.5)
			(layers "F.Cu" "F.Paste" "F.Mask")
			(roundrect_rratio 0.25)
			(net 593 "/Peripherals/SPIO_MISO_CONN")
			(pinfunction "R3.1")
			(pintype "passive")
		)
		(pad "4" smd roundrect
			(at 0.8 0.45 90)
			(size 0.4 0.5)
			(layers "F.Cu" "F.Paste" "F.Mask")
			(roundrect_rratio 0.25)
			(net 655 "unconnected-(R63-R4.1-Pad4)")
			(pinfunction "R4.1")
			(pintype "passive+no_connect")
		)
		(pad "5" smd roundrect
			(at 0.8 -0.452 90)
			(size 0.4 0.5)
			(layers "F.Cu" "F.Paste" "F.Mask")
			(roundrect_rratio 0.25)
			(net 656 "unconnected-(R63-R4.2-Pad5)")
			(pinfunction "R4.2")
			(pintype "passive+no_connect")
		)
		(pad "6" smd roundrect
			(at 0.27 -0.452 90)
			(size 0.4 0.5)
			(layers "F.Cu" "F.Paste" "F.Mask")
			(roundrect_rratio 0.25)
			(net 32 "SPIO_MISO")
			(pinfunction "R3.2")
			(pintype "passive")
		)
		(pad "7" smd roundrect
			(at -0.272 -0.452 90)
			(size 0.4 0.5)
			(layers "F.Cu" "F.Paste" "F.Mask")
			(roundrect_rratio 0.25)
			(net 33 "~{SPI0_CS0}")
			(pinfunction "R2.2")
			(pintype "passive")
		)
		(pad "8" smd roundrect
			(at -0.802 -0.452 90)
			(size 0.4 0.5)
			(layers "F.Cu" "F.Paste" "F.Mask")
			(roundrect_rratio 0.25)
			(net 34 "~{SPI0_CS1}")
			(pinfunction "R1.2")
			(pintype "passive")
		)
	)
	(footprint "antmicro-footprints:LED_0603_1608Metric_G"
		(layer "F.Cu")
		(at 132 101.95 -90)
		(descr "LED SMD 0603 Green")
		(tags "LED SMD 0603 Green")
		(property "Reference" "D1"
			(at -1.2 -0.5 -90)
			(layer "F.SilkS")
			(effects
				(font
					(size 0.7 0.7)
					(thickness 0.15)
				)
				(justify left bottom)
			)
		)
		(property "Value" "LED_G_0603_LTST-C190GKT"
			(at -0.001 1.599 -90)
			(layer "F.Fab")
			(effects
				(font
					(size 0.7 0.7)
					(thickness 0.15)
				)
				(justify left bottom)
			)
		)
		(property "Footprint" "antmicro-footprints:LED_0603_1608Metric_G"
			(at 0 0 -90)
			(layer "F.Fab")
			(hide yes)
			(effects
				(font
					(size 1.27 1.27)
					(thickness 0.15)
				)
			)
		)
		(property "Datasheet" "https://media.digikey.com/pdf/Data%20Sheets/Lite-On%20PDFs/LTST-C190GKT.pdf"
			(at 0 0 -90)
			(layer "F.Fab")
			(hide yes)
			(effects
				(font
					(size 1.27 1.27)
					(thickness 0.15)
				)
			)
		)
		(property "Author" "Antmicro"
			(at 30.05 233.95 0)
			(layer "F.Fab")
			(hide yes)
			(effects
				(font
					(size 1 1)
					(thickness 0.15)
				)
			)
		)
		(property "Color" "Green"
			(at 30.05 233.95 0)
			(layer "F.Fab")
			(hide yes)
			(effects
				(font
					(size 1 1)
					(thickness 0.15)
				)
			)
		)
		(property "License" "Apache-2.0"
			(at 30.05 233.95 0)
			(layer "F.Fab")
			(hide yes)
			(effects
				(font
					(size 1 1)
					(thickness 0.15)
				)
			)
		)
		(property "MPN" "LTST-C190GKT"
			(at 30.05 233.95 0)
			(layer "F.Fab")
			(hide yes)
			(effects
				(font
					(size 1 1)
					(thickness 0.15)
				)
			)
		)
		(property "Manufacturer" "Lite-On"
			(at 30.05 233.95 0)
			(layer "F.Fab")
			(hide yes)
			(effects
				(font
					(size 1 1)
					(thickness 0.15)
				)
			)
		)
		(sheetname "M.2")
		(sheetfile "m-2.kicad_sch")
		(attr smd)
		(fp_line
			(start 0.22 0.35)
			(end -0.22 0.35)
			(stroke
				(width 0.15)
				(type solid)
			)
			(layer "F.SilkS")
		)
		(fp_line
			(start -0.094672 0.201008)
			(end -0.094672 -0.198992)
			(stroke
				(width 0.1)
				(type solid)
			)
			(layer "F.SilkS")
		)
		(fp_line
			(start 0.105328 0.201008)
			(end -0.094672 0.001008)
			(stroke
				(width 0.1)
				(type solid)
			)
			(layer "F.SilkS")
		)
		(fp_line
			(start 0.105328 0.201008)
			(end 0.105328 -0.198992)
			(stroke
				(width 0.1)
				(type solid)
			)
			(layer "F.SilkS")
		)
		(fp_line
			(start -0.094672 0.001008)
			(end -0.24 0.001008)
			(stroke
				(width 0.1)
				(type solid)
			)
			(layer "F.SilkS")
		)
		(fp_line
			(start -0.094672 0.001008)
			(end 0.105328 -0.198992)
			(stroke
				(width 0.1)
				(type solid)
			)
			(layer "F.SilkS")
		)
		(fp_line
			(start 0.105328 0.001008)
			(end 0.24 0.001)
			(stroke
				(width 0.1)
				(type solid)
			)
			(layer "F.SilkS")
		)
		(fp_line
			(start -1.18 -0.319)
			(end -1.18 0.321)
			(stroke
				(width 0.15)
				(type solid)
			)
			(layer "F.SilkS")
		)
		(fp_line
			(start 0.22 -0.35)
			(end -0.22 -0.35)
			(stroke
				(width 0.15)
				(type solid)
			)
			(layer "F.SilkS")
		)
		(fp_rect
			(start 1.25 0.65)
			(end -1.25 -0.65)
			(stroke
				(width 0.05)
				(type solid)
			)
			(fill none)
			(layer "F.CrtYd")
		)
		(fp_line
			(start -0.199 0.2)
			(end -0.199 0.1)
			(stroke
				(width 0.15)
				(type solid)
			)
			(layer "F.Fab")
		)
		(fp_line
			(start 0.201 0.2)
			(end 0.201 0)
			(stroke
				(width 0.15)
				(type solid)
			)
			(layer "F.Fab")
		)
		(fp_line
			(start -0.199 0)
			(end -0.597 0)
			(stroke
				(width 0.15)
				(type solid)
			)
			(layer "F.Fab")
		)
		(fp_line
			(start -0.101 0)
			(end 0.201 0.2)
			(stroke
				(width 0.15)
				(type solid)
			)
			(layer "F.Fab")
		)
		(fp_line
			(start 0.201 0)
			(end 0.201 -0.202)
			(stroke
				(width 0.15)
				(type solid)
			)
			(layer "F.Fab")
		)
		(fp_line
			(start 0.599 0)
			(end 0.201 0)
			(stroke
				(width 0.15)
				(type solid)
			)
			(layer "F.Fab")
		)
		(fp_line
			(start -0.199 -0.202)
			(end -0.199 0.1)
			(stroke
				(width 0.15)
				(type solid)
			)
			(layer "F.Fab")
		)
		(fp_line
			(start 0.201 -0.202)
			(end -0.101 0)
			(stroke
				(width 0.15)
				(type solid)
			)
			(layer "F.Fab")
		)
		(fp_rect
			(start 0.848 0.4)
			(end -0.85 -0.402)
			(stroke
				(width 0.15)
				(type solid)
			)
			(fill none)
			(layer "F.Fab")
		)
		(fp_text user "${REFERENCE}"
			(at -1.4224 5.999 -90)
			(layer "F.Fab")
			(hide yes)
			(effects
				(font
					(size 0.7 0.7)
					(thickness 0.15)
				)
				(justify left bottom)
			)
		)
		(fp_text user "Author: Antmicro"
			(at -1.4224 4.799 -90)
			(layer "F.Fab")
			(hide yes)
			(effects
				(font
					(size 0.7 0.7)
					(thickness 0.15)
				)
				(justify left bottom)
			)
		)
		(fp_text user "License: Apache-2.0"
			(at -1.4224 3.599 -90)
			(layer "F.Fab")
			(hide yes)
			(effects
				(font
					(size 0.7 0.7)
					(thickness 0.15)
				)
				(justify left bottom)
			)
		)
		(pad "1" smd roundrect
			(at -0.7 0 90)
			(size 0.8 1)
			(layers "F.Cu" "F.Paste" "F.Mask")
			(roundrect_rratio 0.2)
			(net 140 "Net-(D1-C)")
			(pinfunction "C")
			(pintype "passive")
		)
		(pad "2" smd roundrect
			(at 0.7 0 90)
			(size 0.8 1)
			(layers "F.Cu" "F.Paste" "F.Mask")
			(roundrect_rratio 0.2)
			(net 141 "Net-(D1-A)")
			(pinfunction "A")
			(pintype "passive")
		)
	)
	(footprint "antmicro-footprints:SW_KMR211NGLFS_SMD"
		(layer "F.Cu")
		(at 104 125.9)
		(property "Reference" "S1"
			(at -3.78 -1.57 0)
			(layer "F.SilkS")
			(effects
				(font
					(size 0.7 0.7)
					(thickness 0.15)
				)
				(justify left bottom)
			)
		)
		(property "Value" "SW_KMR211NGLFS_SMD"
			(at -3 3 0)
			(layer "F.Fab")
			(effects
				(font
					(size 0.7 0.7)
					(thickness 0.15)
				)
				(justify left bottom)
			)
		)
		(property "Footprint" "antmicro-footprints:SW_KMR211NGLFS_SMD"
			(at 0 0 0)
			(layer "F.Fab")
			(hide yes)
			(effects
				(font
					(size 1.27 1.27)
					(thickness 0.15)
				)
			)
		)
		(property "Datasheet" "http://www.farnell.com/datasheets/2631211.pdf"
			(at 0 0 0)
			(layer "F.Fab")
			(hide yes)
			(effects
				(font
					(size 1.27 1.27)
					(thickness 0.15)
				)
			)
		)
		(property "Author" "Antmicro"
			(at 0 0 0)
			(layer "F.Fab")
			(hide yes)
			(effects
				(font
					(size 1 1)
					(thickness 0.15)
				)
			)
		)
		(property "License" "Apache-2.0"
			(at 0 0 0)
			(layer "F.Fab")
			(hide yes)
			(effects
				(font
					(size 1 1)
					(thickness 0.15)
				)
			)
		)
		(property "MPN" "KMR211NGLFS"
			(at 0 0 0)
			(layer "F.Fab")
			(hide yes)
			(effects
				(font
					(size 1 1)
					(thickness 0.15)
				)
			)
		)
		(property "Manufacturer" "C&K"
			(at 0 0 0)
			(layer "F.Fab")
			(hide yes)
			(effects
				(font
					(size 1 1)
					(thickness 0.15)
				)
			)
		)
		(sheetname "SoM")
		(sheetfile "som.kicad_sch")
		(attr smd)
		(fp_line
			(start -2.1 -1.6)
			(end -2.1 -1.499)
			(stroke
				(width 0.15)
				(type solid)
			)
			(layer "F.SilkS")
		)
		(fp_line
			(start -2.1 1.601)
			(end -2.1 1.48)
			(stroke
				(width 0.15)
				(type solid)
			)
			(layer "F.SilkS")
		)
		(fp_line
			(start 2.101 -1.6)
			(end -2.1 -1.6)
			(stroke
				(width 0.15)
				(type solid)
			)
			(layer "F.SilkS")
		)
		(fp_line
			(start 2.101 -1.58)
			(end 2.101 -1.459)
			(stroke
				(width 0.15)
				(type solid)
			)
			(layer "F.SilkS")
		)
		(fp_line
			(start 2.101 1.601)
			(end -2.1 1.601)
			(stroke
				(width 0.15)
				(type solid)
			)
			(layer "F.SilkS")
		)
		(fp_line
			(start 2.101 1.601)
			(end 2.101 1.48)
			(stroke
				(width 0.15)
				(type solid)
			)
			(layer "F.SilkS")
		)
		(fp_rect
			(start 2.751 1.75)
			(end -2.748 -1.749)
			(stroke
				(width 0.05)
				(type solid)
			)
			(fill none)
			(layer "F.CrtYd")
		)
		(fp_line
			(start -2.1 -1.6)
			(end -2.1 1.601)
			(stroke
				(width 0.15)
				(type solid)
			)
			(layer "F.Fab")
		)
		(fp_line
			(start -2.1 1.601)
			(end 2.101 1.601)
			(stroke
				(width 0.15)
				(type solid)
			)
			(layer "F.Fab")
		)
		(fp_line
			(start -0.248 -0.8)
			(end 0.25 -0.8)
			(stroke
				(width 0.15)
				(type solid)
			)
			(layer "F.Fab")
		)
		(fp_line
			(start 0.25 0.802)
			(end -0.248 0.802)
			(stroke
				(width 0.15)
				(type solid)
			)
			(layer "F.Fab")
		)
		(fp_line
			(start 2.101 -1.6)
			(end -2.1 -1.6)
			(stroke
				(width 0.15)
				(type solid)
			)
			(layer "F.Fab")
		)
		(fp_line
			(start 2.101 1.601)
			(end 2.101 -1.6)
			(stroke
				(width 0.15)
				(type solid)
			)
			(layer "F.Fab")
		)
		(fp_arc
			(start -0.248 0.802)
			(mid -1.050001 0.001)
			(end -0.248 -0.8)
			(stroke
				(width 0.15)
				(type solid)
			)
			(layer "F.Fab")
		)
		(fp_arc
			(start 0.25 -0.8)
			(mid 1.051001 0.001)
			(end 0.25 0.802)
			(stroke
				(width 0.15)
				(type solid)
			)
			(layer "F.Fab")
		)
		(fp_text user "${REFERENCE}"
			(at -3 4.25 0)
			(layer "F.Fab")
			(hide yes)
			(effects
				(font
					(size 0.7 0.7)
					(thickness 0.15)
				)
				(justify left bottom)
			)
		)
		(fp_text user "Author: Antmicro"
			(at -3 5.5 0)
			(layer "F.Fab")
			(hide yes)
			(effects
				(font
					(size 0.7 0.7)
					(thickness 0.15)
				)
				(justify left bottom)
			)
		)
		(fp_text user "License: Apache-2.0"
			(at -3 6.75 0)
			(layer "F.Fab")
			(hide yes)
			(effects
				(font
					(size 0.7 0.7)
					(thickness 0.15)
				)
				(justify left bottom)
			)
		)
		(pad "1" smd rect
			(at -2.048 -0.8 180)
			(size 0.9 1)
			(layers "F.Cu" "F.Paste" "F.Mask")
			(net 80 "/SoM/~{FORCE_RECOVERY}")
			(pinfunction "1")
			(pintype "passive")
		)
		(pad "2" smd rect
			(at 2.05 -0.8 180)
			(size 0.9 1)
			(layers "F.Cu" "F.Paste" "F.Mask")
			(net 80 "/SoM/~{FORCE_RECOVERY}")
			(pinfunction "2")
			(pintype "passive")
		)
		(pad "3" smd rect
			(at -2.048 0.802 180)
			(size 0.9 1)
			(layers "F.Cu" "F.Paste" "F.Mask")
			(net 1 "GND")
			(pinfunction "3")
			(pintype "passive")
		)
		(pad "4" smd rect
			(at 2.05 0.802 180)
			(size 0.9 1)
			(layers "F.Cu" "F.Paste" "F.Mask")
			(net 1 "GND")
			(pinfunction "4")
			(pintype "passive")
		)
	)
)
